# COM Express 7 Baseboard — assets/stackup.csv
Name;Type;Material;Thickness[mm];Constant;User-Name
F.Mask;Top Solder Mask;;0.01;;F_Mask
F.Cu;copper;;0.035;;F_Cu
dielectric 1;prepreg;PR2116;0.12;4.2;dielectric 1
In1.Cu;copper;;0.035;;In1_Cu
dielectric 2;core;FR4-Improved;0.2;4.3;dielectric 2
In2.Cu;copper;;0.035;;In2_Cu
dielectric 3 (1/2);prepreg;PR2116;0.12;4.2;dielectric 3 (1/2)
dielectric 3 (2/2);prepreg;PR2116;0.12;4.2;dielectric 3 (2/2)
In3.Cu;copper;;0.035;;In3_Cu
dielectric 4;core;FR4-Improved;0.2;4.3;dielectric 4
In4.Cu;copper;;0.035;;In4_Cu
dielectric 5 (1/2);prepreg;PR2116;0.12;4.2;dielectric 5 (1/2)
dielectric 5 (2/2);prepreg;PR2116;0.12;4.2;dielectric 5 (2/2)
In5.Cu;copper;;0.035;;In5_Cu
dielectric 6;core;FR4-Improved;0.2;4.3;dielectric 6
In6.Cu;copper;;0.035;;In6_Cu
dielectric 7;prepreg;PR2116;0.12;4.2;dielectric 7
B.Cu;copper;;0.035;;B_Cu
B.Mask;Bottom Solder Mask;;0.01;;B_Mask
